# T6G (Grand Teton) — schematic netlist excerpt (pin names and nets, part order shuffled) for the footprints in the layout excerpt that follows; sources: Cadence DE-HDL packaged netlist, KiCad conversion of 04192023_DAF0TMB3IC0_F0TG_MB_C_brd_V02_OCP.brd

J72  PICOPROBE_BXA  DELTA-L 4.0 EMPTY  pkg TRIANG_LAUNCH_3PXB  page 229
  \1_p\  = DELTA_L_85_5INCH_IN2_DN
  \2_n\  = DELTA_L_85_5INCH_IN2_DP
  \3_g\  = DELTA_L_GND_1

(kicad_pcb
	(version 20260206)
	(generator "pcbnew")
	(generator_version "10.0")
	(general
		(thickness 1.6)
		(legacy_teardrops no)
	)
	(paper "A4")
	(title_block
		(title "04192023_DAF0TMB3IC0_F0TG_MB_C_brd_V02_OCP.brd")
		(comment 1 "Grand Teton / footprints 3283-3283 of 8354")
	)
	(layers
		(0 "F.Cu" signal "TOP")
		(4 "In1.Cu" signal "GND")
		(6 "In2.Cu" signal "IN1")
		(8 "In3.Cu" signal "GND1")
		(10 "In4.Cu" signal "IN2")
		(12 "In5.Cu" signal "GND2")
		(14 "In6.Cu" signal "IN3")
		(16 "In7.Cu" signal "GND3")
		(18 "In8.Cu" signal "VCC")
		(20 "In9.Cu" signal "VCC1")
		(22 "In10.Cu" signal "GND4")
		(24 "In11.Cu" signal "IN4")
		(26 "In12.Cu" signal "GND5")
		(28 "In13.Cu" signal "IN5")
		(30 "In14.Cu" signal "GND6")
		(32 "In15.Cu" signal "IN6")
		(34 "In16.Cu" signal "GND7")
		(2 "B.Cu" signal "BOTTOM")
		(9 "F.Adhes" user "F.Adhesive")
		(11 "B.Adhes" user "B.Adhesive")
		(13 "F.Paste" user "Package Geometry/Pastemask Top")
		(15 "B.Paste" user "Package Geometry/Pastemask Bottom")
		(5 "F.SilkS" user "Ref Des/Silkscreen Top")
		(7 "B.SilkS" user "Ref Des/Silkscreen Bottom")
		(1 "F.Mask" user "Board Geometry/Soldermask Top")
		(3 "B.Mask" user "Board Geometry/Soldermask Bottom")
		(17 "Dwgs.User" user "User.Drawings")
		(19 "Cmts.User" user "User.Comments")
		(21 "Eco1.User" user "User.Eco1")
		(23 "Eco2.User" user "User.Eco2")
		(25 "Edge.Cuts" user "Board Geometry/Outline")
		(27 "Margin" user)
		(31 "F.CrtYd" user "Package Geometry/Place Bound Top")
		(29 "B.CrtYd" user "Package Geometry/Place Bound Bottom")
		(35 "F.Fab" user "Ref Des/Assembly Top")
		(33 "B.Fab" user "Ref Des/Assembly Bottom")
	)
	(footprint ""
		(layer "F.Cu")
		(at 389.462264 6.149848)
		(property "Reference" "J72"
			(at -4.619498 0.932434 90)
			(unlocked yes)
			(layer "F.SilkS")
			(effects
				(font
					(size 0.7874 0.5842)
					(thickness 0.1524)
				)
				(justify left)
			)
		)
		(property "Value" ""
			(at 0 0 0)
			(layer "F.Fab")
			(effects
				(font
					(size 1.27 1.27)
				)
			)
		)
		(duplicate_pad_numbers_are_jumpers no)
		(fp_line
			(start -1.2192 -2.06756)
			(end 1.2192 -2.06756)
			(stroke
				(width 0.1524)
				(type default)
			)
			(layer "F.SilkS")
		)
		(fp_line
			(start -1.2192 2.06756)
			(end -1.2192 -2.06756)
			(stroke
				(width 0.1524)
				(type default)
			)
			(layer "F.SilkS")
		)
		(fp_line
			(start 1.2192 -2.06756)
			(end 1.2192 2.06756)
			(stroke
				(width 0.1524)
				(type default)
			)
			(layer "F.SilkS")
		)
		(fp_line
			(start 1.2192 2.06756)
			(end -1.2192 2.06756)
			(stroke
				(width 0.1524)
				(type default)
			)
			(layer "F.SilkS")
		)
		(pad "" np_thru_hole circle
			(at -2.8829 -1.27 270)
			(size 1.0414 1.0414)
			(drill 1.0414)
			(layers "*.Cu" "*.Mask")
			(clearance 0.381)
			(thermal_gap 0.381)
		)
		(pad "" np_thru_hole circle
			(at -2.8829 1.27 270)
			(size 1.0414 1.0414)
			(drill 1.0414)
			(layers "*.Cu" "*.Mask")
			(clearance 0.381)
			(thermal_gap 0.381)
		)
		(pad "" np_thru_hole circle
			(at 3.4671 -1.27 270)
			(size 1.0414 1.0414)
			(drill 1.0414)
			(layers "*.Cu" "*.Mask")
			(clearance 0.381)
			(thermal_gap 0.381)
		)
		(pad "" np_thru_hole circle
			(at 3.4671 1.27 270)
			(size 1.0414 1.0414)
			(drill 1.0414)
			(layers "*.Cu" "*.Mask")
			(clearance 0.381)
			(thermal_gap 0.381)
		)
		(pad "1" smd rect
			(at 0.8255 -0.249936 270)
			(size 0.3048 0.508)
			(layers "F.Cu" "F.Mask" "F.Paste")
			(net "DELTA_L_85_5INCH_IN2_DN")
		)
		(pad "2" smd rect
			(at 0.8255 0.249936 270)
			(size 0.3048 0.508)
			(layers "F.Cu" "F.Mask" "F.Paste")
			(net "DELTA_L_85_5INCH_IN2_DP")
		)
		(pad "3" smd circle
			(at 0 0)
			(size 0 0)
			(layers "F.Cu" "F.Mask" "F.Paste")
			(net "DELTA_L_GND_1")
		)
		(zone
			(layer "F.Cu")
			(hatch none 0.5)
			(connect_pads
				(clearance 0)
			)
			(min_thickness 0.25)
			(keepout
				(tracks not_allowed)
				(vias allowed)
				(pads allowed)
				(copperpour not_allowed)
				(footprints allowed)
			)
			(placement
				(enabled no)
				(sheetname "")
			)
			(fill
				(thermal_gap 0.5)
				(thermal_bridge_width 0.5)
				(island_removal_mode 0)
			)
			(polygon
				(pts
					(xy 390.579864 5.601208) (xy 390.579864 5.696712) (xy 389.982964 5.696712) (xy 389.982964 6.103112)
					(xy 390.579864 6.103112) (xy 390.579864 6.196584) (xy 389.982964 6.196584) (xy 389.982964 6.602984)
					(xy 390.579864 6.602984) (xy 390.579864 6.698488) (xy 389.881364 6.698488) (xy 389.881364 5.601208)
				)
			)
		)
		(zone
			(layers "F.Cu" "B.Cu" "In1.Cu" "In2.Cu" "In3.Cu" "In4.Cu" "In5.Cu" "In6.Cu"
				"In7.Cu" "In8.Cu" "In9.Cu" "In10.Cu" "In11.Cu" "In12.Cu" "In13.Cu" "In14.Cu"
				"In15.Cu" "In16.Cu"
			)
			(hatch none 0.5)
			(connect_pads
				(clearance 0)
			)
			(min_thickness 0.25)
			(keepout
				(tracks not_allowed)
				(vias allowed)
				(pads allowed)
				(copperpour not_allowed)
				(footprints allowed)
			)
			(placement
				(enabled no)
				(sheetname "")
			)
			(fill
				(thermal_gap 0.5)
				(thermal_bridge_width 0.5)
				(island_removal_mode 0)
			)
			(polygon
				(pts
					(arc
						(start 387.506464 4.879848)
						(mid 385.652264 4.879848)
						(end 387.506464 4.879848)
					)
				)
			)
		)
		(zone
			(layers "F.Cu" "B.Cu" "In1.Cu" "In2.Cu" "In3.Cu" "In4.Cu" "In5.Cu" "In6.Cu"
				"In7.Cu" "In8.Cu" "In9.Cu" "In10.Cu" "In11.Cu" "In12.Cu" "In13.Cu" "In14.Cu"
				"In15.Cu" "In16.Cu"
			)
			(hatch none 0.5)
			(connect_pads
				(clearance 0)
			)
			(min_thickness 0.25)
			(keepout
				(tracks not_allowed)
				(vias allowed)
				(pads allowed)
				(copperpour not_allowed)
				(footprints allowed)
			)
			(placement
				(enabled no)
				(sheetname "")
			)
			(fill
				(thermal_gap 0.5)
				(thermal_bridge_width 0.5)
				(island_removal_mode 0)
			)
			(polygon
				(pts
					(arc
						(start 387.506464 7.419848)
						(mid 385.652264 7.419848)
						(end 387.506464 7.419848)
					)
				)
			)
		)
		(zone
			(layers "F.Cu" "B.Cu" "In1.Cu" "In2.Cu" "In3.Cu" "In4.Cu" "In5.Cu" "In6.Cu"
				"In7.Cu" "In8.Cu" "In9.Cu" "In10.Cu" "In11.Cu" "In12.Cu" "In13.Cu" "In14.Cu"
				"In15.Cu" "In16.Cu"
			)
			(hatch none 0.5)
			(connect_pads
				(clearance 0)
			)
			(min_thickness 0.25)
			(keepout
				(tracks not_allowed)
				(vias allowed)
				(pads allowed)
				(copperpour not_allowed)
				(footprints allowed)
			)
			(placement
				(enabled no)
				(sheetname "")
			)
			(fill
				(thermal_gap 0.5)
				(thermal_bridge_width 0.5)
				(island_removal_mode 0)
			)
			(polygon
				(pts
					(arc
						(start 393.856464 4.879848)
						(mid 392.002264 4.879848)
						(end 393.856464 4.879848)
					)
				)
			)
		)
		(zone
			(layers "F.Cu" "B.Cu" "In1.Cu" "In2.Cu" "In3.Cu" "In4.Cu" "In5.Cu" "In6.Cu"
				"In7.Cu" "In8.Cu" "In9.Cu" "In10.Cu" "In11.Cu" "In12.Cu" "In13.Cu" "In14.Cu"
				"In15.Cu" "In16.Cu"
			)
			(hatch none 0.5)
			(connect_pads
				(clearance 0)
			)
			(min_thickness 0.25)
			(keepout
				(tracks not_allowed)
				(vias allowed)
				(pads allowed)
				(copperpour not_allowed)
				(footprints allowed)
			)
			(placement
				(enabled no)
				(sheetname "")
			)
			(fill
				(thermal_gap 0.5)
				(thermal_bridge_width 0.5)
				(island_removal_mode 0)
			)
			(polygon
				(pts
					(arc
						(start 393.856464 7.419848)
						(mid 392.002264 7.419848)
						(end 393.856464 7.419848)
					)
				)
			)
		)
	)
)
